(kicad_pcb
	(version 20260206)
	(generator "pcbnew")
	(generator_version "10.0")
	(general
		(thickness 1.6)
		(legacy_teardrops no)
	)
	(paper "A4")
	(title_block
		(title "Bryce Canyon_R.DPB_16317-1_OCP.brd")
		(comment 1 "Bryce Canyon / footprints 1676-1681 of 2099")
	)
	(layers
		(0 "F.Cu" signal "TOP")
		(4 "In1.Cu" signal "L2GND")
		(6 "In2.Cu" signal "L3")
		(8 "In3.Cu" signal "L4VCC")
		(10 "In4.Cu" signal "L5VCC")
		(12 "In5.Cu" signal "L6")
		(14 "In6.Cu" signal "L7GND")
		(2 "B.Cu" signal "BOTTOM")
		(9 "F.Adhes" user "F.Adhesive")
		(11 "B.Adhes" user "B.Adhesive")
		(13 "F.Paste" user "Package Geometry/Pastemask Top")
		(15 "B.Paste" user "Package Geometry/Pastemask Bottom")
		(5 "F.SilkS" user "Ref Des/Silkscreen Top")
		(7 "B.SilkS" user "Ref Des/Silkscreen Bottom")
		(1 "F.Mask" user "Board Geometry/Soldermask Top")
		(3 "B.Mask" user "Board Geometry/Soldermask Bottom")
		(17 "Dwgs.User" user "User.Drawings")
		(19 "Cmts.User" user "User.Comments")
		(21 "Eco1.User" user "User.Eco1")
		(23 "Eco2.User" user "User.Eco2")
		(25 "Edge.Cuts" user "Board Geometry/Outline")
		(27 "Margin" user)
		(31 "F.CrtYd" user "Package Geometry/Place Bound Top")
		(29 "B.CrtYd" user "Package Geometry/Place Bound Bottom")
		(35 "F.Fab" user "Ref Des/Assembly Top")
		(33 "B.Fab" user "Ref Des/Assembly Bottom")
	)
	(footprint ""
		(layer "F.Cu")
		(at 378.249942 -65.39992)
		(property "Reference" "LED21"
			(at 0 0 0)
			(layer "F.SilkS")
			(hide yes)
			(effects
				(font
					(size 1.27 1.27)
				)
			)
		)
		(property "Value" "LED-BY-19-GP"
			(at -2.132076 1.414018 0)
			(unlocked yes)
			(layer "F.Fab")
			(hide yes)
			(effects
				(font
					(size 1.016 1.016)
					(thickness 0.1524)
				)
			)
		)
		(property "Device Type" "LED-1615-4PH26"
			(at -2.132076 -0.109982 0)
			(unlocked yes)
			(layer "F.Fab")
			(hide yes)
			(effects
				(font
					(size 1.016 1.016)
					(thickness 0.1524)
				)
			)
		)
		(duplicate_pad_numbers_are_jumpers no)
		(fp_line
			(start -1.2954 0.254)
			(end -1.2954 1.6002)
			(stroke
				(width 0.508)
				(type default)
			)
			(layer "F.SilkS")
		)
		(fp_line
			(start -1.2954 1.6002)
			(end 1.2954 1.6002)
			(stroke
				(width 0.508)
				(type default)
			)
			(layer "F.SilkS")
		)
		(fp_line
			(start -1.1176 -1.4224)
			(end 1.1176 -1.4224)
			(stroke
				(width 0.1524)
				(type default)
			)
			(layer "F.SilkS")
		)
		(fp_line
			(start -1.1176 1.4224)
			(end -1.1176 -1.4224)
			(stroke
				(width 0.1524)
				(type default)
			)
			(layer "F.SilkS")
		)
		(fp_line
			(start 1.1176 -1.4224)
			(end 1.1176 1.4224)
			(stroke
				(width 0.1524)
				(type default)
			)
			(layer "F.SilkS")
		)
		(fp_line
			(start 1.1176 1.4224)
			(end -1.1176 1.4224)
			(stroke
				(width 0.1524)
				(type default)
			)
			(layer "F.SilkS")
		)
		(fp_line
			(start 1.2954 1.6002)
			(end 1.2954 0.254)
			(stroke
				(width 0.508)
				(type default)
			)
			(layer "F.SilkS")
		)
		(fp_rect
			(start -0.7493 0.8001)
			(end 0.7493 -0.8001)
			(stroke
				(width 0)
				(type default)
			)
			(fill no)
			(layer "F.CrtYd")
		)
		(fp_poly
			(pts
				(xy -1.3716 1.6764) (xy -1.3716 -1.6764) (xy 1.3716 -1.6764) (xy 1.3716 0.0635) (xy 0.7493 0.0635)
				(xy 0.7493 -0.8001) (xy -0.7493 -0.8001) (xy -0.7493 0.8001) (xy 0.7493 0.8001) (xy 0.7493 0.0762)
				(xy 1.3716 0.0762) (xy 1.3716 1.6764)
			)
			(stroke
				(width 0)
				(type default)
			)
			(fill no)
			(layer "F.CrtYd")
		)
		(fp_rect
			(start -1.3716 1.6764)
			(end 1.3716 -1.6764)
			(stroke
				(width 0)
				(type default)
			)
			(fill no)
			(layer "F.Fab")
		)
		(pad "1" smd rect
			(at 0.50038 -0.73025)
			(size 0.7112 0.8636)
			(layers "F.Cu" "F.Mask" "F.Paste")
			(net "DRV_ACT_20")
		)
		(pad "2" smd rect
			(at -0.50038 -0.73025)
			(size 0.7112 0.8636)
			(layers "F.Cu" "F.Mask" "F.Paste")
			(net "FLT_HDD20")
		)
		(pad "3" smd rect
			(at 0.50038 0.73025)
			(size 0.7112 0.8636)
			(layers "F.Cu" "F.Mask" "F.Paste")
			(net "DRV_ACT_20_N")
		)
		(pad "4" smd rect
			(at -0.50038 0.73025)
			(size 0.7112 0.8636)
			(layers "F.Cu" "F.Mask" "F.Paste")
			(net "FLT_HDD20_N")
		)
	)
	(footprint ""
		(layer "F.Cu")
		(at 181.356 -11.049 180)
		(property "Reference" "R751"
			(at 0 0 180)
			(layer "F.SilkS")
			(hide yes)
			(effects
				(font
					(size 1.27 1.27)
				)
			)
		)
		(property "Value" "4K7R2J-2-GP"
			(at 0.064008 -3.993896 180)
			(unlocked yes)
			(layer "F.Fab")
			(hide yes)
			(effects
				(font
					(size 1.016 1.016)
					(thickness 0.1524)
				)
			)
		)
		(property "Device Type" "R402H16"
			(at 0.064008 -5.517896 180)
			(unlocked yes)
			(layer "F.Fab")
			(hide yes)
			(effects
				(font
					(size 1.016 1.016)
					(thickness 0.1524)
				)
			)
		)
		(duplicate_pad_numbers_are_jumpers no)
		(fp_line
			(start 0.508 -0.9398)
			(end -0.508 -0.9398)
			(stroke
				(width 0.1524)
				(type default)
			)
			(layer "F.SilkS")
		)
		(fp_line
			(start -0.508 -0.9398)
			(end -0.508 0.9398)
			(stroke
				(width 0.1524)
				(type default)
			)
			(layer "F.SilkS")
		)
		(fp_rect
			(start -0.508 0.9398)
			(end 0.508 -0.9398)
			(stroke
				(width 0)
				(type default)
			)
			(fill no)
			(layer "F.CrtYd")
		)
		(fp_rect
			(start -0.508 0.9398)
			(end 0.508 -0.9398)
			(stroke
				(width 0)
				(type default)
			)
			(fill no)
			(layer "F.Fab")
		)
		(pad "1" smd custom
			(at 0 -0.4445 180)
			(size 0.1397 0.1397)
			(layers "F.Cu" "F.Mask" "F.Paste")
			(net "P12V_B")
			(options
				(clearance outline)
				(anchor circle)
			)
			(primitives
				(gr_poly
					(pts
						(arc
							(start -0.1778 -0.2794)
							(mid -0.249642 -0.249642)
							(end -0.2794 -0.1778)
						)
						(arc
							(start -0.2794 0.1778)
							(mid -0.249642 0.249642)
							(end -0.1778 0.2794)
						)
						(arc
							(start 0.1778 0.2794)
							(mid 0.249642 0.249642)
							(end 0.2794 0.1778)
						)
						(arc
							(start 0.2794 -0.1778)
							(mid 0.249642 -0.249642)
							(end 0.1778 -0.2794)
						)
					)
					(width 0)
					(fill yes)
				)
			)
		)
		(pad "2" smd custom
			(at 0 0.4445 180)
			(size 0.1397 0.1397)
			(layers "F.Cu" "F.Mask" "F.Paste")
			(net "SW_HDD_R29")
			(options
				(clearance outline)
				(anchor circle)
			)
			(primitives
				(gr_poly
					(pts
						(arc
							(start -0.1778 -0.2794)
							(mid -0.249642 -0.249642)
							(end -0.2794 -0.1778)
						)
						(arc
							(start -0.2794 0.1778)
							(mid -0.249642 0.249642)
							(end -0.1778 0.2794)
						)
						(arc
							(start 0.1778 0.2794)
							(mid 0.249642 0.249642)
							(end 0.2794 0.1778)
						)
						(arc
							(start 0.2794 -0.1778)
							(mid 0.249642 -0.249642)
							(end 0.1778 -0.2794)
						)
					)
					(width 0)
					(fill yes)
				)
			)
		)
	)
	(footprint ""
		(layer "F.Cu")
		(at 336.677 -33.02)
		(property "Reference" "Q156"
			(at 0 0 0)
			(layer "F.SilkS")
			(hide yes)
			(effects
				(font
					(size 1.27 1.27)
				)
			)
		)
		(property "Value" "AO4407AL-GP"
			(at -3.707384 -1.5367 0)
			(unlocked yes)
			(layer "F.Fab")
			(hide yes)
			(effects
				(font
					(size 1.016 1.016)
					(thickness 0.1524)
				)
			)
		)
		(property "Device Type" "SOIC8H69"
			(at -3.707384 -3.0607 0)
			(unlocked yes)
			(layer "F.Fab")
			(hide yes)
			(effects
				(font
					(size 1.016 1.016)
					(thickness 0.1524)
				)
			)
		)
		(duplicate_pad_numbers_are_jumpers no)
		(fp_line
			(start -2.7432 -1.4224)
			(end -2.7432 1.4224)
			(stroke
				(width 0.1524)
				(type default)
			)
			(layer "F.SilkS")
		)
		(fp_line
			(start -2.7432 1.4224)
			(end -2.6416 1.4224)
			(stroke
				(width 0.1524)
				(type default)
			)
			(layer "F.SilkS")
		)
		(fp_line
			(start -2.7432 1.4224)
			(end 2.1336 1.4224)
			(stroke
				(width 0.1524)
				(type default)
			)
			(layer "F.SilkS")
		)
		(fp_line
			(start -2.7178 -0.508)
			(end -2.1844 -0.0508)
			(stroke
				(width 0.1524)
				(type default)
			)
			(layer "F.SilkS")
		)
		(fp_line
			(start -2.6289 3.4417)
			(end -2.6289 1.4732)
			(stroke
				(width 0.381)
				(type default)
			)
			(layer "F.SilkS")
		)
		(fp_line
			(start -2.1844 -0.0508)
			(end -2.7178 0.508)
			(stroke
				(width 0.1524)
				(type default)
			)
			(layer "F.SilkS")
		)
		(fp_line
			(start 2.1336 -1.4224)
			(end -2.7432 -1.4224)
			(stroke
				(width 0.1524)
				(type default)
			)
			(layer "F.SilkS")
		)
		(fp_line
			(start 2.1336 1.4224)
			(end 2.1336 -1.4224)
			(stroke
				(width 0.1524)
				(type default)
			)
			(layer "F.SilkS")
		)
		(fp_poly
			(pts
				(xy -2.2098 -1.4224) (xy -2.2098 1.4224) (xy 2.2098 1.4224) (xy 2.2098 -1.4224)
			)
			(stroke
				(width 0)
				(type default)
			)
			(fill yes)
			(layer "F.SilkS")
		)
		(fp_rect
			(start -2.450084 2.999994)
			(end 2.450084 -2.999994)
			(stroke
				(width 0)
				(type default)
			)
			(fill no)
			(layer "F.CrtYd")
		)
		(fp_poly
			(pts
				(xy -2.8194 3.6322) (xy -2.8194 -3.6322) (xy 2.8194 -3.6322) (xy 2.8194 1.18364) (xy 2.450084 1.18364)
				(xy 2.450084 -2.999994) (xy -2.450084 -2.999994) (xy -2.450084 2.999994) (xy 2.450084 2.999994)
				(xy 2.450084 1.18618) (xy 2.8194 1.18618) (xy 2.8194 3.6322)
			)
			(stroke
				(width 0)
				(type default)
			)
			(fill no)
			(layer "F.CrtYd")
		)
		(fp_rect
			(start -2.8194 3.6322)
			(end 2.8194 -3.6322)
			(stroke
				(width 0)
				(type default)
			)
			(fill no)
			(layer "F.Fab")
		)
		(pad "1" smd rect
			(at -1.905 2.54)
			(size 0.635 1.651)
			(layers "F.Cu" "F.Mask" "F.Paste")
			(net "P12V_B")
		)
		(pad "2" smd rect
			(at -0.635 2.54)
			(size 0.635 1.651)
			(layers "F.Cu" "F.Mask" "F.Paste")
			(net "P12V_B")
		)
		(pad "3" smd rect
			(at 0.635 2.54)
			(size 0.635 1.651)
			(layers "F.Cu" "F.Mask" "F.Paste")
			(net "P12V_B")
		)
		(pad "4" smd rect
			(at 1.905 2.54)
			(size 0.635 1.651)
			(layers "F.Cu" "F.Mask" "F.Paste")
			(net "SW_HDD_N30")
		)
		(pad "5" smd rect
			(at 1.905 -2.54)
			(size 0.635 1.651)
			(layers "F.Cu" "F.Mask" "F.Paste")
			(net "P12V_HDD30")
		)
		(pad "6" smd rect
			(at 0.635 -2.54)
			(size 0.635 1.651)
			(layers "F.Cu" "F.Mask" "F.Paste")
			(net "P12V_HDD30")
		)
		(pad "7" smd rect
			(at -0.635 -2.54)
			(size 0.635 1.651)
			(layers "F.Cu" "F.Mask" "F.Paste")
			(net "P12V_HDD30")
		)
		(pad "8" smd rect
			(at -1.905 -2.54)
			(size 0.635 1.651)
			(layers "F.Cu" "F.Mask" "F.Paste")
			(net "P12V_HDD30")
		)
	)
	(footprint ""
		(layer "F.Cu")
		(at 105.407968 -214.784178 90)
		(property "Reference" "Q246"
			(at 0 0 90)
			(layer "F.SilkS")
			(hide yes)
			(effects
				(font
					(size 1.27 1.27)
				)
			)
		)
		(property "Value" "SSM3K324R-GP"
			(at 0.127 -8.9662 90)
			(unlocked yes)
			(layer "F.Fab")
			(hide yes)
			(effects
				(font
					(size 1.016 1.016)
					(thickness 0.1524)
				)
			)
		)
		(property "Device Type" "SOT23DGS2D4H35"
			(at 0.127 -10.4902 90)
			(unlocked yes)
			(layer "F.Fab")
			(hide yes)
			(effects
				(font
					(size 1.016 1.016)
					(thickness 0.1524)
				)
			)
		)
		(duplicate_pad_numbers_are_jumpers no)
		(fp_line
			(start 1.651 -1.778)
			(end -1.651 -1.778)
			(stroke
				(width 0.1524)
				(type default)
			)
			(layer "F.SilkS")
		)
		(fp_line
			(start -1.651 -1.778)
			(end -1.651 1.778)
			(stroke
				(width 0.1524)
				(type default)
			)
			(layer "F.SilkS")
		)
		(fp_line
			(start 1.651 1.778)
			(end 1.651 -1.778)
			(stroke
				(width 0.1524)
				(type default)
			)
			(layer "F.SilkS")
		)
		(fp_line
			(start -1.651 1.778)
			(end 1.651 1.778)
			(stroke
				(width 0.1524)
				(type default)
			)
			(layer "F.SilkS")
		)
		(fp_poly
			(pts
				(xy -1.778 1.8796) (xy -1.778 -1.8796) (xy 1.778 -1.8796) (xy 1.778 1.8796)
			)
			(stroke
				(width 0)
				(type default)
			)
			(fill no)
			(layer "F.CrtYd")
		)
		(fp_poly
			(pts
				(xy -1.778 1.8796) (xy -1.778 -1.8796) (xy 1.778 -1.8796) (xy 1.778 1.8796)
			)
			(stroke
				(width 0)
				(type default)
			)
			(fill no)
			(layer "F.Fab")
		)
		(pad "D" smd custom
			(at 0 -0.9525 90)
			(size 0.1905 0.1905)
			(layers "F.Cu" "F.Mask" "F.Paste")
			(net "DRV_ACT_3_N")
			(options
				(clearance outline)
				(anchor circle)
			)
			(primitives
				(gr_poly
					(pts
						(arc
							(start -0.1778 0.5715)
							(mid -0.321484 0.511984)
							(end -0.381 0.3683)
						)
						(arc
							(start -0.381 -0.3683)
							(mid -0.321484 -0.511984)
							(end -0.1778 -0.5715)
						)
						(arc
							(start 0.1778 -0.5715)
							(mid 0.321484 -0.511984)
							(end 0.381 -0.3683)
						)
						(arc
							(start 0.381 0.3683)
							(mid 0.321484 0.511984)
							(end 0.1778 0.5715)
						)
					)
					(width 0)
					(fill yes)
				)
			)
		)
		(pad "G" smd custom
			(at -0.98425 0.9525 90)
			(size 0.1905 0.1905)
			(layers "F.Cu" "F.Mask" "F.Paste")
			(net "DRIVE_B_3_ACT")
			(options
				(clearance outline)
				(anchor circle)
			)
			(primitives
				(gr_poly
					(pts
						(arc
							(start -0.1778 0.5715)
							(mid -0.321484 0.511984)
							(end -0.381 0.3683)
						)
						(arc
							(start -0.381 -0.3683)
							(mid -0.321484 -0.511984)
							(end -0.1778 -0.5715)
						)
						(arc
							(start 0.1778 -0.5715)
							(mid 0.321484 -0.511984)
							(end 0.381 -0.3683)
						)
						(arc
							(start 0.381 0.3683)
							(mid 0.321484 0.511984)
							(end 0.1778 0.5715)
						)
					)
					(width 0)
					(fill yes)
				)
			)
		)
		(pad "S" smd custom
			(at 0.98425 0.9525 90)
			(size 0.1905 0.1905)
			(layers "F.Cu" "F.Mask" "F.Paste")
			(net "GND")
			(options
				(clearance outline)
				(anchor circle)
			)
			(primitives
				(gr_poly
					(pts
						(arc
							(start -0.1778 0.5715)
							(mid -0.321484 0.511984)
							(end -0.381 0.3683)
						)
						(arc
							(start -0.381 -0.3683)
							(mid -0.321484 -0.511984)
							(end -0.1778 -0.5715)
						)
						(arc
							(start 0.1778 -0.5715)
							(mid 0.321484 -0.511984)
							(end 0.381 -0.3683)
						)
						(arc
							(start 0.381 0.3683)
							(mid 0.321484 0.511984)
							(end 0.1778 0.5715)
						)
					)
					(width 0)
					(fill yes)
				)
			)
		)
	)
	(footprint ""
		(layer "F.Cu")
		(at 353.184714 -129.66065 -90)
		(property "Reference" "C276"
			(at 0 0 270)
			(layer "F.SilkS")
			(hide yes)
			(effects
				(font
					(size 1.27 1.27)
				)
			)
		)
		(property "Value" "SCD01U16V1KX-GP"
			(at -2.8321 -1.7399 270)
			(unlocked yes)
			(layer "F.Fab")
			(hide yes)
			(effects
				(font
					(size 1.016 1.016)
					(thickness 0.1524)
				)
			)
		)
		(property "Device Type" "C0201H13"
			(at -2.8321 -3.2639 270)
			(unlocked yes)
			(layer "F.Fab")
			(hide yes)
			(effects
				(font
					(size 1.016 1.016)
					(thickness 0.1524)
				)
			)
		)
		(duplicate_pad_numbers_are_jumpers no)
		(fp_rect
			(start -0.2794 0.6477)
			(end 0.2794 -0.6477)
			(stroke
				(width 0)
				(type default)
			)
			(fill no)
			(layer "F.CrtYd")
		)
		(fp_rect
			(start -0.2794 0.6477)
			(end 0.2794 -0.6477)
			(stroke
				(width 0)
				(type default)
			)
			(fill no)
			(layer "F.Fab")
		)
		(pad "1" smd custom
			(at 0 -0.2794 270)
			(size 0.0762 0.0762)
			(layers "F.Cu" "F.Mask" "F.Paste")
			(net "SAS_HDD_RX_P19")
			(options
				(clearance outline)
				(anchor circle)
			)
			(primitives
				(gr_poly
					(pts
						(arc
							(start 0.1524 -0.127)
							(mid 0.137521 -0.162921)
							(end 0.1016 -0.1778)
						)
						(arc
							(start -0.1016 -0.1778)
							(mid -0.137521 -0.162921)
							(end -0.1524 -0.127)
						)
						(arc
							(start -0.1524 0.127)
							(mid -0.137521 0.162921)
							(end -0.1016 0.1778)
						)
						(arc
							(start 0.1016 0.1778)
							(mid 0.137521 0.162921)
							(end 0.1524 0.127)
						)
					)
					(width 0)
					(fill yes)
				)
			)
		)
		(pad "2" smd custom
			(at 0 0.2794 270)
			(size 0.0762 0.0762)
			(layers "F.Cu" "F.Mask" "F.Paste")
			(net "PHY_SCC_B_TO_DRV_B_19_DP")
			(options
				(clearance outline)
				(anchor circle)
			)
			(primitives
				(gr_poly
					(pts
						(arc
							(start 0.1524 -0.127)
							(mid 0.137521 -0.162921)
							(end 0.1016 -0.1778)
						)
						(arc
							(start -0.1016 -0.1778)
							(mid -0.137521 -0.162921)
							(end -0.1524 -0.127)
						)
						(arc
							(start -0.1524 0.127)
							(mid -0.137521 0.162921)
							(end -0.1016 0.1778)
						)
						(arc
							(start 0.1016 0.1778)
							(mid 0.137521 0.162921)
							(end 0.1524 0.127)
						)
					)
					(width 0)
					(fill yes)
				)
			)
		)
	)
	(footprint ""
		(layer "F.Cu")
		(at 140.7414 -99.7712 180)
		(property "Reference" "Q235"
			(at 0 0 180)
			(layer "F.SilkS")
			(hide yes)
			(effects
				(font
					(size 1.27 1.27)
				)
			)
		)
		(property "Value" "2N7002K-2-GP"
			(at 0.127 -8.9662 180)
			(unlocked yes)
			(layer "F.Fab")
			(hide yes)
			(effects
				(font
					(size 1.016 1.016)
					(thickness 0.1524)
				)
			)
		)
		(property "Device Type" "SOT23DGS2D4H44"
			(at 0.127 -10.4902 180)
			(unlocked yes)
			(layer "F.Fab")
			(hide yes)
			(effects
				(font
					(size 1.016 1.016)
					(thickness 0.1524)
				)
			)
		)
		(duplicate_pad_numbers_are_jumpers no)
		(fp_line
			(start 1.651 1.778)
			(end 1.651 -1.778)
			(stroke
				(width 0.1524)
				(type default)
			)
			(layer "F.SilkS")
		)
		(fp_line
			(start 1.651 -1.778)
			(end -1.651 -1.778)
			(stroke
				(width 0.1524)
				(type default)
			)
			(layer "F.SilkS")
		)
		(fp_line
			(start -1.651 1.778)
			(end 1.651 1.778)
			(stroke
				(width 0.1524)
				(type default)
			)
			(layer "F.SilkS")
		)
		(fp_line
			(start -1.651 -1.778)
			(end -1.651 1.778)
			(stroke
				(width 0.1524)
				(type default)
			)
			(layer "F.SilkS")
		)
		(fp_poly
			(pts
				(xy -1.778 1.8796) (xy -1.778 -1.8796) (xy 1.778 -1.8796) (xy 1.778 1.8796)
			)
			(stroke
				(width 0)
				(type default)
			)
			(fill no)
			(layer "F.CrtYd")
		)
		(fp_poly
			(pts
				(xy -1.778 1.8796) (xy -1.778 -1.8796) (xy 1.778 -1.8796) (xy 1.778 1.8796)
			)
			(stroke
				(width 0)
				(type default)
			)
			(fill no)
			(layer "F.Fab")
		)
		(pad "D" smd custom
			(at 0 -0.9525 180)
			(size 0.1905 0.1905)
			(layers "F.Cu" "F.Mask" "F.Paste")
			(net "FLT_HDD16_N")
			(options
				(clearance outline)
				(anchor circle)
			)
			(primitives
				(gr_poly
					(pts
						(arc
							(start -0.1778 0.5715)
							(mid -0.321484 0.511984)
							(end -0.381 0.3683)
						)
						(arc
							(start -0.381 -0.3683)
							(mid -0.321484 -0.511984)
							(end -0.1778 -0.5715)
						)
						(arc
							(start 0.1778 -0.5715)
							(mid 0.321484 -0.511984)
							(end 0.381 -0.3683)
						)
						(arc
							(start 0.381 0.3683)
							(mid 0.321484 0.511984)
							(end 0.1778 0.5715)
						)
					)
					(width 0)
					(fill yes)
				)
			)
		)
		(pad "G" smd custom
			(at -0.98425 0.9525 180)
			(size 0.1905 0.1905)
			(layers "F.Cu" "F.Mask" "F.Paste")
			(net "DRIVE_B_16_FLT_LED")
			(options
				(clearance outline)
				(anchor circle)
			)
			(primitives
				(gr_poly
					(pts
						(arc
							(start -0.1778 0.5715)
							(mid -0.321484 0.511984)
							(end -0.381 0.3683)
						)
						(arc
							(start -0.381 -0.3683)
							(mid -0.321484 -0.511984)
							(end -0.1778 -0.5715)
						)
						(arc
							(start 0.1778 -0.5715)
							(mid 0.321484 -0.511984)
							(end 0.381 -0.3683)
						)
						(arc
							(start 0.381 0.3683)
							(mid 0.321484 0.511984)
							(end 0.1778 0.5715)
						)
					)
					(width 0)
					(fill yes)
				)
			)
		)
		(pad "S" smd custom
			(at 0.98425 0.9525 180)
			(size 0.1905 0.1905)
			(layers "F.Cu" "F.Mask" "F.Paste")
			(net "GND")
			(options
				(clearance outline)
				(anchor circle)
			)
			(primitives
				(gr_poly
					(pts
						(arc
							(start -0.1778 0.5715)
							(mid -0.321484 0.511984)
							(end -0.381 0.3683)
						)
						(arc
							(start -0.381 -0.3683)
							(mid -0.321484 -0.511984)
							(end -0.1778 -0.5715)
						)
						(arc
							(start 0.1778 -0.5715)
							(mid 0.321484 -0.511984)
							(end 0.381 -0.3683)
						)
						(arc
							(start 0.381 0.3683)
							(mid 0.321484 0.511984)
							(end 0.1778 0.5715)
						)
					)
					(width 0)
					(fill yes)
				)
			)
		)
	)
)
